# T6G (Grand Teton) — schematic netlist excerpt (pin names and nets, part order shuffled) for the footprints in the layout excerpt that follows; sources: Cadence DE-HDL packaged netlist, KiCad conversion of 04192023_DAF0TMB3IC0_F0TG_MB_C_brd_V02_OCP.brd

PC607_SOP0_3  Q_CAP  2.2UF 10V 10% X6S  pkg C0402  page 199 : A = PVDDCR_CPU0_P0_PVCC ; B = GND
R1045  Q_RES  0 5% EMPTY  pkg 0402LF  page 301 : A = P1V8_CPU0_RT2_1A_1D ; B = P1V8_CPU0_RT2_1A

(kicad_pcb
	(version 20260206)
	(generator "pcbnew")
	(generator_version "10.0")
	(general
		(thickness 1.6)
		(legacy_teardrops no)
	)
	(paper "A4")
	(title_block
		(title "04192023_DAF0TMB3IC0_F0TG_MB_C_brd_V02_OCP.brd")
		(comment 1 "Grand Teton / footprints 4347-4348 of 8354")
	)
	(layers
		(0 "F.Cu" signal "TOP")
		(4 "In1.Cu" signal "GND")
		(6 "In2.Cu" signal "IN1")
		(8 "In3.Cu" signal "GND1")
		(10 "In4.Cu" signal "IN2")
		(12 "In5.Cu" signal "GND2")
		(14 "In6.Cu" signal "IN3")
		(16 "In7.Cu" signal "GND3")
		(18 "In8.Cu" signal "VCC")
		(20 "In9.Cu" signal "VCC1")
		(22 "In10.Cu" signal "GND4")
		(24 "In11.Cu" signal "IN4")
		(26 "In12.Cu" signal "GND5")
		(28 "In13.Cu" signal "IN5")
		(30 "In14.Cu" signal "GND6")
		(32 "In15.Cu" signal "IN6")
		(34 "In16.Cu" signal "GND7")
		(2 "B.Cu" signal "BOTTOM")
		(9 "F.Adhes" user "F.Adhesive")
		(11 "B.Adhes" user "B.Adhesive")
		(13 "F.Paste" user "Package Geometry/Pastemask Top")
		(15 "B.Paste" user "Package Geometry/Pastemask Bottom")
		(5 "F.SilkS" user "Ref Des/Silkscreen Top")
		(7 "B.SilkS" user "Ref Des/Silkscreen Bottom")
		(1 "F.Mask" user "Board Geometry/Soldermask Top")
		(3 "B.Mask" user "Board Geometry/Soldermask Bottom")
		(17 "Dwgs.User" user "User.Drawings")
		(19 "Cmts.User" user "User.Comments")
		(21 "Eco1.User" user "User.Eco1")
		(23 "Eco2.User" user "User.Eco2")
		(25 "Edge.Cuts" user "Board Geometry/Outline")
		(27 "Margin" user)
		(31 "F.CrtYd" user "Package Geometry/Place Bound Top")
		(29 "B.CrtYd" user "Package Geometry/Place Bound Bottom")
		(35 "F.Fab" user "Ref Des/Assembly Top")
		(33 "B.Fab" user "Ref Des/Assembly Bottom")
	)
	(footprint ""
		(layer "F.Cu")
		(at 426.469556 -396.145004 180)
		(property "Reference" "R1045"
			(at 0 0 180)
			(layer "F.SilkS")
			(hide yes)
			(effects
				(font
					(size 1.27 1.27)
				)
			)
		)
		(property "Value" ""
			(at 0 0 180)
			(layer "F.Fab")
			(effects
				(font
					(size 1.27 1.27)
				)
			)
		)
		(duplicate_pad_numbers_are_jumpers no)
		(fp_line
			(start 0.7874 0.4064)
			(end -0.7874 0.4064)
			(stroke
				(width 0.1524)
				(type default)
			)
			(layer "F.SilkS")
		)
		(fp_line
			(start 0.7874 -0.4064)
			(end 0.7874 0.4064)
			(stroke
				(width 0.1524)
				(type default)
			)
			(layer "F.SilkS")
		)
		(fp_line
			(start -0.7874 0.4064)
			(end -0.7874 -0.4064)
			(stroke
				(width 0.1524)
				(type default)
			)
			(layer "F.SilkS")
		)
		(fp_line
			(start -0.7874 -0.4064)
			(end 0.7874 -0.4064)
			(stroke
				(width 0.1524)
				(type default)
			)
			(layer "F.SilkS")
		)
		(fp_line
			(start 0.67945 0.3048)
			(end 0.120396 0.3048)
			(stroke
				(width 0.1)
				(type default)
			)
			(layer "F.Fab")
		)
		(fp_line
			(start 0.67945 -0.3048)
			(end 0.67945 0.3048)
			(stroke
				(width 0.1)
				(type default)
			)
			(layer "F.Fab")
		)
		(fp_line
			(start 0.12065 -0.2794)
			(end 0.12065 -0.3048)
			(stroke
				(width 0.1)
				(type default)
			)
			(layer "F.Fab")
		)
		(fp_line
			(start 0.12065 -0.3048)
			(end 0.67945 -0.3048)
			(stroke
				(width 0.1)
				(type default)
			)
			(layer "F.Fab")
		)
		(fp_line
			(start 0.120396 0.3048)
			(end 0.120396 0.2794)
			(stroke
				(width 0.1)
				(type default)
			)
			(layer "F.Fab")
		)
		(fp_line
			(start 0.120396 0.2794)
			(end -0.12065 0.2794)
			(stroke
				(width 0.1)
				(type default)
			)
			(layer "F.Fab")
		)
		(fp_line
			(start -0.12065 0.3048)
			(end -0.67945 0.3048)
			(stroke
				(width 0.1)
				(type default)
			)
			(layer "F.Fab")
		)
		(fp_line
			(start -0.12065 0.2794)
			(end -0.12065 0.3048)
			(stroke
				(width 0.1)
				(type default)
			)
			(layer "F.Fab")
		)
		(fp_line
			(start -0.12065 -0.2794)
			(end 0.12065 -0.2794)
			(stroke
				(width 0.1)
				(type default)
			)
			(layer "F.Fab")
		)
		(fp_line
			(start -0.12065 -0.305054)
			(end -0.12065 -0.2794)
			(stroke
				(width 0.1)
				(type default)
			)
			(layer "F.Fab")
		)
		(fp_line
			(start -0.67945 0.3048)
			(end -0.67945 -0.305054)
			(stroke
				(width 0.1)
				(type default)
			)
			(layer "F.Fab")
		)
		(fp_line
			(start -0.67945 -0.305054)
			(end -0.12065 -0.305054)
			(stroke
				(width 0.1)
				(type default)
			)
			(layer "F.Fab")
		)
		(pad "1" smd rect
			(at -0.40005 0)
			(size 0.4572 0.508)
			(layers "F.Cu" "F.Mask" "F.Paste")
			(net "P1V8_CPU0_RT2_1A_1D")
		)
		(pad "2" smd rect
			(at 0.40005 0)
			(size 0.4572 0.508)
			(layers "F.Cu" "F.Mask" "F.Paste")
			(net "P1V8_CPU0_RT2_1A")
		)
	)
	(footprint ""
		(layer "F.Cu")
		(at 418.212778 -163.769548 90)
		(property "Reference" "PC607_SOP0_3"
			(at 0 0 90)
			(layer "F.SilkS")
			(hide yes)
			(effects
				(font
					(size 1.27 1.27)
				)
			)
		)
		(property "Value" ""
			(at 0 0 90)
			(layer "F.Fab")
			(effects
				(font
					(size 1.27 1.27)
				)
			)
		)
		(duplicate_pad_numbers_are_jumpers no)
		(fp_line
			(start 0.7874 -0.4064)
			(end 0.7874 0.4064)
			(stroke
				(width 0.1524)
				(type default)
			)
			(layer "F.SilkS")
		)
		(fp_line
			(start -0.7874 -0.4064)
			(end 0.7874 -0.4064)
			(stroke
				(width 0.1524)
				(type default)
			)
			(layer "F.SilkS")
		)
		(fp_line
			(start 0.7874 0.4064)
			(end -0.7874 0.4064)
			(stroke
				(width 0.1524)
				(type default)
			)
			(layer "F.SilkS")
		)
		(fp_line
			(start -0.7874 0.4064)
			(end -0.7874 -0.4064)
			(stroke
				(width 0.1524)
				(type default)
			)
			(layer "F.SilkS")
		)
		(fp_line
			(start -0.12065 -0.305054)
			(end -0.12065 -0.2794)
			(stroke
				(width 0.1)
				(type default)
			)
			(layer "F.Fab")
		)
		(fp_line
			(start -0.67945 -0.305054)
			(end -0.12065 -0.305054)
			(stroke
				(width 0.1)
				(type default)
			)
			(layer "F.Fab")
		)
		(fp_line
			(start 0.67945 -0.3048)
			(end 0.67945 0.3048)
			(stroke
				(width 0.1)
				(type default)
			)
			(layer "F.Fab")
		)
		(fp_line
			(start 0.12065 -0.3048)
			(end 0.67945 -0.3048)
			(stroke
				(width 0.1)
				(type default)
			)
			(layer "F.Fab")
		)
		(fp_line
			(start 0.12065 -0.2794)
			(end 0.12065 -0.3048)
			(stroke
				(width 0.1)
				(type default)
			)
			(layer "F.Fab")
		)
		(fp_line
			(start -0.12065 -0.2794)
			(end 0.12065 -0.2794)
			(stroke
				(width 0.1)
				(type default)
			)
			(layer "F.Fab")
		)
		(fp_line
			(start 0.120396 0.2794)
			(end -0.12065 0.2794)
			(stroke
				(width 0.1)
				(type default)
			)
			(layer "F.Fab")
		)
		(fp_line
			(start -0.12065 0.2794)
			(end -0.12065 0.3048)
			(stroke
				(width 0.1)
				(type default)
			)
			(layer "F.Fab")
		)
		(fp_line
			(start 0.67945 0.3048)
			(end 0.120396 0.3048)
			(stroke
				(width 0.1)
				(type default)
			)
			(layer "F.Fab")
		)
		(fp_line
			(start 0.120396 0.3048)
			(end 0.120396 0.2794)
			(stroke
				(width 0.1)
				(type default)
			)
			(layer "F.Fab")
		)
		(fp_line
			(start -0.12065 0.3048)
			(end -0.67945 0.3048)
			(stroke
				(width 0.1)
				(type default)
			)
			(layer "F.Fab")
		)
		(fp_line
			(start -0.67945 0.3048)
			(end -0.67945 -0.305054)
			(stroke
				(width 0.1)
				(type default)
			)
			(layer "F.Fab")
		)
		(pad "1" smd circle
			(at -0.40005 0 90)
			(size 0 0)
			(layers "F.Cu" "F.Mask" "F.Paste")
			(net "PVDDCR_CPU0_P0_PVCC")
		)
		(pad "2" smd circle
			(at 0.40005 0 90)
			(size 0 0)
			(layers "F.Cu" "F.Mask" "F.Paste")
			(net "GND")
		)
	)
)
